(kicad_pcb
	(version 20260206)
	(generator "pcbnew")
	(generator_version "10.0")
	(general
		(thickness 1.6)
		(legacy_teardrops no)
	)
	(paper "A4")
	(title_block
		(title "03242023_DA0F0TMBIJ0_F0T_Motherboard_J_brd_V01_OCP.brd")
		(comment 1 "Grand Teton / footprint 461 of 6105 (J9), pads 1-112 of 291")
	)
	(layers
		(0 "F.Cu" signal "TOP")
		(4 "In1.Cu" signal "GND")
		(6 "In2.Cu" signal "IN1")
		(8 "In3.Cu" signal "GND1")
		(10 "In4.Cu" signal "IN2")
		(12 "In5.Cu" signal "GND2")
		(14 "In6.Cu" signal "IN3")
		(16 "In7.Cu" signal "GND3")
		(18 "In8.Cu" signal "VCC")
		(20 "In9.Cu" signal "VCC1")
		(22 "In10.Cu" signal "GND4")
		(24 "In11.Cu" signal "IN4")
		(26 "In12.Cu" signal "GND5")
		(28 "In13.Cu" signal "IN5")
		(30 "In14.Cu" signal "GND6")
		(32 "In15.Cu" signal "IN6")
		(34 "In16.Cu" signal "GND7")
		(2 "B.Cu" signal "BOTTOM")
		(9 "F.Adhes" user "F.Adhesive")
		(11 "B.Adhes" user "B.Adhesive")
		(13 "F.Paste" user "Package Geometry/Pastemask Top")
		(15 "B.Paste" user "Package Geometry/Pastemask Bottom")
		(5 "F.SilkS" user "Ref Des/Silkscreen Top")
		(7 "B.SilkS" user "Ref Des/Silkscreen Bottom")
		(1 "F.Mask" user "Board Geometry/Soldermask Top")
		(3 "B.Mask" user "Board Geometry/Soldermask Bottom")
		(17 "Dwgs.User" user "User.Drawings")
		(19 "Cmts.User" user "User.Comments")
		(21 "Eco1.User" user "User.Eco1")
		(23 "Eco2.User" user "User.Eco2")
		(25 "Edge.Cuts" user "Board Geometry/Outline")
		(27 "Margin" user)
		(31 "F.CrtYd" user "Package Geometry/Place Bound Top")
		(29 "B.CrtYd" user "Package Geometry/Place Bound Bottom")
		(35 "F.Fab" user "Ref Des/Assembly Top")
		(33 "B.Fab" user "Ref Des/Assembly Bottom")
	)
	(footprint ""
		(layer "F.Cu")
		(at 416.347148 -258.091686)
		(property "Reference" "J9"
			(at -3.683 -81.702148 0)
			(unlocked yes)
			(layer "F.SilkS")
			(effects
				(font
					(size 0.7874 0.5842)
					(thickness 0.1524)
				)
				(justify left)
			)
		)
		(property "Value" ""
			(at 0 0 0)
			(layer "F.Fab")
			(effects
				(font
					(size 1.27 1.27)
				)
			)
		)
		(duplicate_pad_numbers_are_jumpers no)
		(pad "1" smd rect
			(at -2.050034 -63.324994 270)
			(size 0.519938 1.4986)
			(layers "F.Cu" "F.Mask" "F.Paste")
			(net "P12V_S3_AUX_CPU0_NVDIMM")
		)
		(pad "2" smd rect
			(at -2.050034 -62.47511 270)
			(size 0.519938 1.4986)
			(layers "F.Cu" "F.Mask" "F.Paste")
			(net "TP_CHE_CPU0_DIMM1_FRU_0")
		)
		(pad "3" smd rect
			(at -2.050034 -61.624972 270)
			(size 0.519938 1.4986)
			(layers "F.Cu" "F.Mask" "F.Paste")
			(net "P3V3_AUX")
		)
		(pad "4" smd rect
			(at -2.050034 -60.775088 270)
			(size 0.519938 1.4986)
			(layers "F.Cu" "F.Mask" "F.Paste")
			(net "I3C_SPD_DDREFGH_CPU0_LVC1_SCL_R")
		)
		(pad "5" smd rect
			(at -2.050034 -59.92495 270)
			(size 0.519938 1.4986)
			(layers "F.Cu" "F.Mask" "F.Paste")
			(net "I3C_SPD_DDREFGH_CPU0_LVC1_SDA")
		)
		(pad "6" smd rect
			(at -2.050034 -59.075066 270)
			(size 0.519938 1.4986)
			(layers "F.Cu" "F.Mask" "F.Paste")
			(net "GND")
		)
		(pad "7" smd rect
			(at -2.050034 -58.224928 270)
			(size 0.519938 1.4986)
			(layers "F.Cu" "F.Mask" "F.Paste")
			(net "M_E_CPU0_SA_DQ<0>")
		)
		(pad "8" smd rect
			(at -2.050034 -57.375044 270)
			(size 0.519938 1.4986)
			(layers "F.Cu" "F.Mask" "F.Paste")
			(net "GND")
		)
		(pad "9" smd rect
			(at -2.050034 -56.524906 270)
			(size 0.519938 1.4986)
			(layers "F.Cu" "F.Mask" "F.Paste")
			(net "M_E_CPU0_SA_DQ<1>")
		)
		(pad "10" smd rect
			(at -2.050034 -55.675022 270)
			(size 0.519938 1.4986)
			(layers "F.Cu" "F.Mask" "F.Paste")
			(net "GND")
		)
		(pad "11" smd rect
			(at -2.050034 -54.824884 270)
			(size 0.519938 1.4986)
			(layers "F.Cu" "F.Mask" "F.Paste")
			(net "M_E_CPU0_SA_DQS_DP<0>")
		)
		(pad "12" smd rect
			(at -2.050034 -53.975 270)
			(size 0.519938 1.4986)
			(layers "F.Cu" "F.Mask" "F.Paste")
			(net "M_E_CPU0_SA_DQS_DN<0>")
		)
		(pad "13" smd rect
			(at -2.050034 -53.125116 270)
			(size 0.519938 1.4986)
			(layers "F.Cu" "F.Mask" "F.Paste")
			(net "GND")
		)
		(pad "14" smd rect
			(at -2.050034 -52.274978 270)
			(size 0.519938 1.4986)
			(layers "F.Cu" "F.Mask" "F.Paste")
			(net "M_E_CPU0_SA_DQ<4>")
		)
		(pad "15" smd rect
			(at -2.050034 -51.425094 270)
			(size 0.519938 1.4986)
			(layers "F.Cu" "F.Mask" "F.Paste")
			(net "GND")
		)
		(pad "16" smd rect
			(at -2.050034 -50.574956 270)
			(size 0.519938 1.4986)
			(layers "F.Cu" "F.Mask" "F.Paste")
			(net "M_E_CPU0_SA_DQ<5>")
		)
		(pad "17" smd rect
			(at -2.050034 -49.725072 270)
			(size 0.519938 1.4986)
			(layers "F.Cu" "F.Mask" "F.Paste")
			(net "GND")
		)
		(pad "18" smd rect
			(at -2.050034 -48.874934 270)
			(size 0.519938 1.4986)
			(layers "F.Cu" "F.Mask" "F.Paste")
			(net "M_E_CPU0_SA_DQ<8>")
		)
		(pad "19" smd rect
			(at -2.050034 -48.02505 270)
			(size 0.519938 1.4986)
			(layers "F.Cu" "F.Mask" "F.Paste")
			(net "GND")
		)
		(pad "20" smd rect
			(at -2.050034 -47.174912 270)
			(size 0.519938 1.4986)
			(layers "F.Cu" "F.Mask" "F.Paste")
			(net "M_E_CPU0_SA_DQ<9>")
		)
		(pad "21" smd rect
			(at -2.050034 -46.325028 270)
			(size 0.519938 1.4986)
			(layers "F.Cu" "F.Mask" "F.Paste")
			(net "GND")
		)
		(pad "22" smd rect
			(at -2.050034 -45.47489 270)
			(size 0.519938 1.4986)
			(layers "F.Cu" "F.Mask" "F.Paste")
			(net "M_E_CPU0_SA_DQS_DP<1>")
		)
		(pad "23" smd rect
			(at -2.050034 -44.625006 270)
			(size 0.519938 1.4986)
			(layers "F.Cu" "F.Mask" "F.Paste")
			(net "M_E_CPU0_SA_DQS_DN<1>")
		)
		(pad "24" smd rect
			(at -2.050034 -43.775122 270)
			(size 0.519938 1.4986)
			(layers "F.Cu" "F.Mask" "F.Paste")
			(net "GND")
		)
		(pad "25" smd rect
			(at -2.050034 -42.924984 270)
			(size 0.519938 1.4986)
			(layers "F.Cu" "F.Mask" "F.Paste")
			(net "M_E_CPU0_SA_DQ<12>")
		)
		(pad "26" smd rect
			(at -2.050034 -42.0751 270)
			(size 0.519938 1.4986)
			(layers "F.Cu" "F.Mask" "F.Paste")
			(net "GND")
		)
		(pad "27" smd rect
			(at -2.050034 -41.224962 270)
			(size 0.519938 1.4986)
			(layers "F.Cu" "F.Mask" "F.Paste")
			(net "M_E_CPU0_SA_DQ<13>")
		)
		(pad "28" smd rect
			(at -2.050034 -40.375078 270)
			(size 0.519938 1.4986)
			(layers "F.Cu" "F.Mask" "F.Paste")
			(net "GND")
		)
		(pad "29" smd rect
			(at -2.050034 -39.52494 270)
			(size 0.519938 1.4986)
			(layers "F.Cu" "F.Mask" "F.Paste")
			(net "M_E_CPU0_SA_DQ<16>")
		)
		(pad "30" smd rect
			(at -2.050034 -38.675056 270)
			(size 0.519938 1.4986)
			(layers "F.Cu" "F.Mask" "F.Paste")
			(net "GND")
		)
		(pad "31" smd rect
			(at -2.050034 -37.824918 270)
			(size 0.519938 1.4986)
			(layers "F.Cu" "F.Mask" "F.Paste")
			(net "M_E_CPU0_SA_DQ<17>")
		)
		(pad "32" smd rect
			(at -2.050034 -36.975034 270)
			(size 0.519938 1.4986)
			(layers "F.Cu" "F.Mask" "F.Paste")
			(net "GND")
		)
		(pad "33" smd rect
			(at -2.050034 -36.124896 270)
			(size 0.519938 1.4986)
			(layers "F.Cu" "F.Mask" "F.Paste")
			(net "M_E_CPU0_SA_DQS_DP<2>")
		)
		(pad "34" smd rect
			(at -2.050034 -35.275012 270)
			(size 0.519938 1.4986)
			(layers "F.Cu" "F.Mask" "F.Paste")
			(net "M_E_CPU0_SA_DQS_DN<2>")
		)
		(pad "35" smd rect
			(at -2.050034 -34.425128 270)
			(size 0.519938 1.4986)
			(layers "F.Cu" "F.Mask" "F.Paste")
			(net "GND")
		)
		(pad "36" smd rect
			(at -2.050034 -33.57499 270)
			(size 0.519938 1.4986)
			(layers "F.Cu" "F.Mask" "F.Paste")
			(net "M_E_CPU0_SA_DQ<20>")
		)
		(pad "37" smd rect
			(at -2.050034 -32.725106 270)
			(size 0.519938 1.4986)
			(layers "F.Cu" "F.Mask" "F.Paste")
			(net "GND")
		)
		(pad "38" smd rect
			(at -2.050034 -31.874968 270)
			(size 0.519938 1.4986)
			(layers "F.Cu" "F.Mask" "F.Paste")
			(net "M_E_CPU0_SA_DQ<21>")
		)
		(pad "39" smd rect
			(at -2.050034 -31.025084 270)
			(size 0.519938 1.4986)
			(layers "F.Cu" "F.Mask" "F.Paste")
			(net "GND")
		)
		(pad "40" smd rect
			(at -2.050034 -30.174946 270)
			(size 0.519938 1.4986)
			(layers "F.Cu" "F.Mask" "F.Paste")
			(net "M_E_CPU0_SA_DQ<24>")
		)
		(pad "41" smd rect
			(at -2.050034 -29.325062 270)
			(size 0.519938 1.4986)
			(layers "F.Cu" "F.Mask" "F.Paste")
			(net "GND")
		)
		(pad "42" smd rect
			(at -2.050034 -28.474924 270)
			(size 0.519938 1.4986)
			(layers "F.Cu" "F.Mask" "F.Paste")
			(net "M_E_CPU0_SA_DQ<25>")
		)
		(pad "43" smd rect
			(at -2.050034 -27.62504 270)
			(size 0.519938 1.4986)
			(layers "F.Cu" "F.Mask" "F.Paste")
			(net "GND")
		)
		(pad "44" smd rect
			(at -2.050034 -26.774902 270)
			(size 0.519938 1.4986)
			(layers "F.Cu" "F.Mask" "F.Paste")
			(net "M_E_CPU0_SA_DQS_DP<3>")
		)
		(pad "45" smd rect
			(at -2.050034 -25.925018 270)
			(size 0.519938 1.4986)
			(layers "F.Cu" "F.Mask" "F.Paste")
			(net "M_E_CPU0_SA_DQS_DN<3>")
		)
		(pad "46" smd rect
			(at -2.050034 -25.07488 270)
			(size 0.519938 1.4986)
			(layers "F.Cu" "F.Mask" "F.Paste")
			(net "GND")
		)
		(pad "47" smd rect
			(at -2.050034 -24.224996 270)
			(size 0.519938 1.4986)
			(layers "F.Cu" "F.Mask" "F.Paste")
			(net "M_E_CPU0_SA_DQ<28>")
		)
		(pad "48" smd rect
			(at -2.050034 -23.375112 270)
			(size 0.519938 1.4986)
			(layers "F.Cu" "F.Mask" "F.Paste")
			(net "GND")
		)
		(pad "49" smd rect
			(at -2.050034 -22.524974 270)
			(size 0.519938 1.4986)
			(layers "F.Cu" "F.Mask" "F.Paste")
			(net "M_E_CPU0_SA_DQ<29>")
		)
		(pad "50" smd rect
			(at -2.050034 -21.67509 270)
			(size 0.519938 1.4986)
			(layers "F.Cu" "F.Mask" "F.Paste")
			(net "GND")
		)
		(pad "51" smd rect
			(at -2.050034 -20.824952 270)
			(size 0.519938 1.4986)
			(layers "F.Cu" "F.Mask" "F.Paste")
			(net "M_E_CPU0_SA_CB<0>")
		)
		(pad "52" smd rect
			(at -2.050034 -19.975068 270)
			(size 0.519938 1.4986)
			(layers "F.Cu" "F.Mask" "F.Paste")
			(net "GND")
		)
		(pad "53" smd rect
			(at -2.050034 -19.12493 270)
			(size 0.519938 1.4986)
			(layers "F.Cu" "F.Mask" "F.Paste")
			(net "M_E_CPU0_SA_CB<1>")
		)
		(pad "54" smd rect
			(at -2.050034 -18.275046 270)
			(size 0.519938 1.4986)
			(layers "F.Cu" "F.Mask" "F.Paste")
			(net "GND")
		)
		(pad "55" smd rect
			(at -2.050034 -17.424908 270)
			(size 0.519938 1.4986)
			(layers "F.Cu" "F.Mask" "F.Paste")
			(net "M_E_CPU0_SA_DQS_DP<4>")
		)
		(pad "56" smd rect
			(at -2.050034 -16.575024 270)
			(size 0.519938 1.4986)
			(layers "F.Cu" "F.Mask" "F.Paste")
			(net "M_E_CPU0_SA_DQS_DN<4>")
		)
		(pad "57" smd rect
			(at -2.050034 -15.724886 270)
			(size 0.519938 1.4986)
			(layers "F.Cu" "F.Mask" "F.Paste")
			(net "GND")
		)
		(pad "58" smd rect
			(at -2.050034 -14.875002 270)
			(size 0.519938 1.4986)
			(layers "F.Cu" "F.Mask" "F.Paste")
			(net "M_E_CPU0_SA_CB<4>")
		)
		(pad "59" smd rect
			(at -2.050034 -14.025118 270)
			(size 0.519938 1.4986)
			(layers "F.Cu" "F.Mask" "F.Paste")
			(net "GND")
		)
		(pad "60" smd rect
			(at -2.050034 -13.17498 270)
			(size 0.519938 1.4986)
			(layers "F.Cu" "F.Mask" "F.Paste")
			(net "M_E_CPU0_SA_CB<5>")
		)
		(pad "61" smd rect
			(at -2.050034 -12.325096 270)
			(size 0.519938 1.4986)
			(layers "F.Cu" "F.Mask" "F.Paste")
			(net "GND")
		)
		(pad "62" smd rect
			(at -2.050034 -11.474958 270)
			(size 0.519938 1.4986)
			(layers "F.Cu" "F.Mask" "F.Paste")
			(net "M_E_CPU0_ALERT_N")
		)
		(pad "63" smd rect
			(at -2.050034 -10.625074 270)
			(size 0.519938 1.4986)
			(layers "F.Cu" "F.Mask" "F.Paste")
			(net "GND")
		)
		(pad "64" smd rect
			(at -2.050034 -9.774936 270)
			(size 0.519938 1.4986)
			(layers "F.Cu" "F.Mask" "F.Paste")
			(net "M_E_CPU0_SA_CS_N<0>")
		)
		(pad "65" smd rect
			(at -2.050034 -8.925052 270)
			(size 0.519938 1.4986)
			(layers "F.Cu" "F.Mask" "F.Paste")
			(net "GND")
		)
		(pad "66" smd rect
			(at -2.050034 -8.074914 270)
			(size 0.519938 1.4986)
			(layers "F.Cu" "F.Mask" "F.Paste")
			(net "M_E_CPU0_SA_CA<0>")
		)
		(pad "67" smd rect
			(at -2.050034 -7.22503 270)
			(size 0.519938 1.4986)
			(layers "F.Cu" "F.Mask" "F.Paste")
			(net "GND")
		)
		(pad "68" smd rect
			(at -2.050034 -6.374892 270)
			(size 0.519938 1.4986)
			(layers "F.Cu" "F.Mask" "F.Paste")
			(net "M_E_CPU0_SA_CA<2>")
		)
		(pad "69" smd rect
			(at -2.050034 -5.525008 270)
			(size 0.519938 1.4986)
			(layers "F.Cu" "F.Mask" "F.Paste")
			(net "GND")
		)
		(pad "70" smd rect
			(at -2.050034 -4.675124 270)
			(size 0.519938 1.4986)
			(layers "F.Cu" "F.Mask" "F.Paste")
			(net "M_E_CPU0_SA_CA<4>")
		)
		(pad "71" smd rect
			(at -2.050034 -3.824986 270)
			(size 0.519938 1.4986)
			(layers "F.Cu" "F.Mask" "F.Paste")
			(net "GND")
		)
		(pad "72" smd rect
			(at -2.050034 -2.975102 270)
			(size 0.519938 1.4986)
			(layers "F.Cu" "F.Mask" "F.Paste")
			(net "M_E_CPU0_SA_CA<6>")
		)
		(pad "73" smd rect
			(at -2.050034 -2.124964 270)
			(size 0.519938 1.4986)
			(layers "F.Cu" "F.Mask" "F.Paste")
			(net "GND")
		)
		(pad "74" smd rect
			(at -2.050034 -1.27508 270)
			(size 0.519938 1.4986)
			(layers "F.Cu" "F.Mask" "F.Paste")
			(net "M_E_CPU0_SA_PAR")
		)
		(pad "75" smd rect
			(at -2.050034 -0.424942 270)
			(size 0.519938 1.4986)
			(layers "F.Cu" "F.Mask" "F.Paste")
			(net "GND")
		)
		(pad "76" smd rect
			(at -2.050034 5.525008 270)
			(size 0.519938 1.4986)
			(layers "F.Cu" "F.Mask" "F.Paste")
			(net "M_E_CPU0_SB_CA<0>")
		)
		(pad "77" smd rect
			(at -2.050034 6.374892 270)
			(size 0.519938 1.4986)
			(layers "F.Cu" "F.Mask" "F.Paste")
			(net "GND")
		)
		(pad "78" smd rect
			(at -2.050034 7.22503 270)
			(size 0.519938 1.4986)
			(layers "F.Cu" "F.Mask" "F.Paste")
			(net "M_E_CPU0_SB_CA<2>")
		)
		(pad "79" smd rect
			(at -2.050034 8.074914 270)
			(size 0.519938 1.4986)
			(layers "F.Cu" "F.Mask" "F.Paste")
			(net "GND")
		)
		(pad "80" smd rect
			(at -2.050034 8.925052 270)
			(size 0.519938 1.4986)
			(layers "F.Cu" "F.Mask" "F.Paste")
			(net "M_E_CPU0_SB_CA<4>")
		)
		(pad "81" smd rect
			(at -2.050034 9.774936 270)
			(size 0.519938 1.4986)
			(layers "F.Cu" "F.Mask" "F.Paste")
			(net "GND")
		)
		(pad "82" smd rect
			(at -2.050034 10.625074 270)
			(size 0.519938 1.4986)
			(layers "F.Cu" "F.Mask" "F.Paste")
			(net "M_E_CPU0_SB_CA<6>")
		)
		(pad "83" smd rect
			(at -2.050034 11.474958 270)
			(size 0.519938 1.4986)
			(layers "F.Cu" "F.Mask" "F.Paste")
			(net "GND")
		)
		(pad "84" smd rect
			(at -2.050034 12.325096 270)
			(size 0.519938 1.4986)
			(layers "F.Cu" "F.Mask" "F.Paste")
			(net "M_E_CPU0_SB_CS_N<0>")
		)
		(pad "85" smd rect
			(at -2.050034 13.17498 270)
			(size 0.519938 1.4986)
			(layers "F.Cu" "F.Mask" "F.Paste")
			(net "GND")
		)
		(pad "86" smd rect
			(at -2.050034 14.025118 270)
			(size 0.519938 1.4986)
			(layers "F.Cu" "F.Mask" "F.Paste")
			(net "M_E_CPU0_SA_RSP<0>")
		)
		(pad "87" smd rect
			(at -2.050034 14.875002 270)
			(size 0.519938 1.4986)
			(layers "F.Cu" "F.Mask" "F.Paste")
			(net "M_E_CPU0_SB_RSP<0>")
		)
		(pad "88" smd rect
			(at -2.050034 15.724886 270)
			(size 0.519938 1.4986)
			(layers "F.Cu" "F.Mask" "F.Paste")
			(net "GND")
		)
		(pad "89" smd rect
			(at -2.050034 16.575024 270)
			(size 0.519938 1.4986)
			(layers "F.Cu" "F.Mask" "F.Paste")
			(net "M_E_CPU0_SB_CB<4>")
		)
		(pad "90" smd rect
			(at -2.050034 17.424908 270)
			(size 0.519938 1.4986)
			(layers "F.Cu" "F.Mask" "F.Paste")
			(net "GND")
		)
		(pad "91" smd rect
			(at -2.050034 18.275046 270)
			(size 0.519938 1.4986)
			(layers "F.Cu" "F.Mask" "F.Paste")
			(net "M_E_CPU0_SB_CB<5>")
		)
		(pad "92" smd rect
			(at -2.050034 19.12493 270)
			(size 0.519938 1.4986)
			(layers "F.Cu" "F.Mask" "F.Paste")
			(net "GND")
		)
		(pad "93" smd rect
			(at -2.050034 19.975068 270)
			(size 0.519938 1.4986)
			(layers "F.Cu" "F.Mask" "F.Paste")
			(net "M_E_CPU0_SB_DQS_DP<9>")
		)
		(pad "94" smd rect
			(at -2.050034 20.824952 270)
			(size 0.519938 1.4986)
			(layers "F.Cu" "F.Mask" "F.Paste")
			(net "M_E_CPU0_SB_DQS_DN<9>")
		)
		(pad "95" smd rect
			(at -2.050034 21.67509 270)
			(size 0.519938 1.4986)
			(layers "F.Cu" "F.Mask" "F.Paste")
			(net "GND")
		)
		(pad "96" smd rect
			(at -2.050034 22.524974 270)
			(size 0.519938 1.4986)
			(layers "F.Cu" "F.Mask" "F.Paste")
			(net "M_E_CPU0_SB_CB<0>")
		)
		(pad "97" smd rect
			(at -2.050034 23.375112 270)
			(size 0.519938 1.4986)
			(layers "F.Cu" "F.Mask" "F.Paste")
			(net "GND")
		)
		(pad "98" smd rect
			(at -2.050034 24.224996 270)
			(size 0.519938 1.4986)
			(layers "F.Cu" "F.Mask" "F.Paste")
			(net "M_E_CPU0_SB_CB<1>")
		)
		(pad "99" smd rect
			(at -2.050034 25.07488 270)
			(size 0.519938 1.4986)
			(layers "F.Cu" "F.Mask" "F.Paste")
			(net "GND")
		)
		(pad "100" smd rect
			(at -2.050034 25.925018 270)
			(size 0.519938 1.4986)
			(layers "F.Cu" "F.Mask" "F.Paste")
			(net "M_E_CPU0_SB_DQ<0>")
		)
		(pad "101" smd rect
			(at -2.050034 26.774902 270)
			(size 0.519938 1.4986)
			(layers "F.Cu" "F.Mask" "F.Paste")
			(net "GND")
		)
		(pad "102" smd rect
			(at -2.050034 27.62504 270)
			(size 0.519938 1.4986)
			(layers "F.Cu" "F.Mask" "F.Paste")
			(net "M_E_CPU0_SB_DQ<1>")
		)
		(pad "103" smd rect
			(at -2.050034 28.474924 270)
			(size 0.519938 1.4986)
			(layers "F.Cu" "F.Mask" "F.Paste")
			(net "GND")
		)
		(pad "104" smd rect
			(at -2.050034 29.325062 270)
			(size 0.519938 1.4986)
			(layers "F.Cu" "F.Mask" "F.Paste")
			(net "M_E_CPU0_SB_DQS_DP<0>")
		)
		(pad "105" smd rect
			(at -2.050034 30.174946 270)
			(size 0.519938 1.4986)
			(layers "F.Cu" "F.Mask" "F.Paste")
			(net "M_E_CPU0_SB_DQS_DN<0>")
		)
		(pad "106" smd rect
			(at -2.050034 31.025084 270)
			(size 0.519938 1.4986)
			(layers "F.Cu" "F.Mask" "F.Paste")
			(net "GND")
		)
		(pad "107" smd rect
			(at -2.050034 31.874968 270)
			(size 0.519938 1.4986)
			(layers "F.Cu" "F.Mask" "F.Paste")
			(net "M_E_CPU0_SB_DQ<4>")
		)
		(pad "108" smd rect
			(at -2.050034 32.725106 270)
			(size 0.519938 1.4986)
			(layers "F.Cu" "F.Mask" "F.Paste")
			(net "GND")
		)
		(pad "109" smd rect
			(at -2.050034 33.57499 270)
			(size 0.519938 1.4986)
			(layers "F.Cu" "F.Mask" "F.Paste")
			(net "M_E_CPU0_SB_DQ<5>")
		)
		(pad "110" smd rect
			(at -2.050034 34.425128 270)
			(size 0.519938 1.4986)
			(layers "F.Cu" "F.Mask" "F.Paste")
			(net "GND")
		)
		(pad "111" smd rect
			(at -2.050034 35.275012 270)
			(size 0.519938 1.4986)
			(layers "F.Cu" "F.Mask" "F.Paste")
			(net "M_E_CPU0_SB_DQ<8>")
		)
		(pad "112" smd rect
			(at -2.050034 36.124896 270)
			(size 0.519938 1.4986)
			(layers "F.Cu" "F.Mask" "F.Paste")
			(net "GND")
		)
	)
)
